FILE_TYPE = MACRO_DRAWING;
SET COLOR_WIRE YELLOW;
SET COLOR_PROP ORANGE;
SET COLOR_DOT WHITE;
SET COLOR_ARC YELLOW;
SET COLOR_BODY GREEN;
SET COLOR_NOTE PURPLE;
SET PROP_DISPLAY VALUE;
SET PAGE_NUMBER P9;
FORCEADD QUANTA_TITLE_BLOCK_C..1
(-100 100);
FORCEPROP 1 LAST CUSTOM_TXT_CDS <NAME_2>
J 0
(-3275 150);
FORCEPROP 1 LAST CUSTOM_TXT_CDS <NAME_1>
J 0
(-3275 275);
FORCEPROP 1 LAST CUSTOM_TXT_CDS <Q_NUMBER>
J 0
(-1503 203);
DISPLAY 1.212766 (-1503 203);
FORCEPROP 1 LAST CUSTOM_TXT_CDS <Q_PROJ>
J 0
(-2482 202);
DISPLAY 1.212766 (-2482 202);
FORCEPROP 1 LAST CUSTOM_TXT_CDS <Q_REV>
J 0
(-284 203);
DISPLAY 1.212766 (-284 203);
FORCEPROP 1 LAST CUSTOM_TXT_CDS <CON_LAST_MODIFIED>
J 0
(-1985 115);
DISPLAY 0.978723 (-1985 115);
FORCEPROP 1 LAST CUSTOM_TXT_CDS <CON_PAGE_NUM> OF <CON_TOTAL_PAGES>
J 0
(-546 118);
DISPLAY 0.978723 (-546 118);
FORCEPROP 1 LAST Q_TITLE BLOCK DIAGRAM - POWER SEQUENCE
J 0
(-9375 150);
DISPLAY 2.446809 (-9375 150);
PAINT GREEN (-9375 150);
FORCEPROP 1 LAST Q_DEPT BU9
J 1
(-3863 149);
DISPLAY 1.957447 (-3863 149);
PAINT GREEN (-3863 149);
FORCEPROP 2 LAST PAGE_BORDER TRUE
J 0
(-7990 5350);
DISPLAY 0.638298 (-7990 5350);
PAINT PINK (-7990 5350);
DISPLAY INVISIBLE (-7990 5350);
FORCEPROP 1 LAST CDS_LMAN_SYM_OUTLINE -9475,6775,100,-125
J 0
(-100 100);
DISPLAY 0.468085 (-100 100);
PAINT GREEN (-100 100);
DISPLAY INVISIBLE (-100 100);
FORCEPROP 2 LAST CDS_LIB pure_quanta
J 0
(-100 100);
DISPLAY INVISIBLE (-100 100);
FORCEPROP 1 LAST COMMENT_BODY TRUE
J 0
(-88 87);
DISPLAY 0.978723 (-88 87);
PAINT GREEN (-88 87);
DISPLAY INVISIBLE (-88 87);
FORCEPROP 2 LAST CDS_XR_PAGE_TITLE CR-9 : @T6G_MB_LIB.T6G(SCH_1):PAGE9
J 0
(-7990 5350);
DISPLAY 0.638298 (-7990 5350);
PAINT PINK (-7990 5350);
DISPLAY INVISIBLE (-7990 5350);
FORCEPROP 2 LAST CUSTOM_TXT_CDS <XR_PAGE_TITLE>
J 0
(-7990 5350);
DISPLAY 0.638298 (-7990 5350);
PAINT PINK (-7990 5350);
DISPLAY INVISIBLE (-7990 5350);
FORCEPROP 0 LAST CDS_CON_LAST_MODIFIED Tue Mar 08 15:46:35 2022
J 0
(-1985 115);
DISPLAY INVISIBLE (-1985 115);
QUIT
